(kicad_pcb
	(version 20260206)
	(generator "pcbnew")
	(generator_version "10.0")
	(general
		(thickness 1.6)
		(legacy_teardrops no)
	)
	(paper "A4")
	(title_block
		(title "peb — Lightning_PEB_BRD.brd")
		(comment 1 "Lightning (Wiwynn / Facebook NVMe JBOF) / footprints 777-784 of 2563")
	)
	(layers
		(0 "F.Cu" signal "TOP")
		(4 "In1.Cu" signal "L2GND")
		(6 "In2.Cu" signal "L3")
		(8 "In3.Cu" signal "L4VCC")
		(10 "In4.Cu" signal "L5VCC")
		(12 "In5.Cu" signal "L6")
		(14 "In6.Cu" signal "L7GND")
		(2 "B.Cu" signal "BOTTOM")
		(9 "F.Adhes" user "F.Adhesive")
		(11 "B.Adhes" user "B.Adhesive")
		(13 "F.Paste" user "Package Geometry/Pastemask Top")
		(15 "B.Paste" user "Package Geometry/Pastemask Bottom")
		(5 "F.SilkS" user "Ref Des/Silkscreen Top")
		(7 "B.SilkS" user "Ref Des/Silkscreen Bottom")
		(1 "F.Mask" user "Board Geometry/Soldermask Top")
		(3 "B.Mask" user "Board Geometry/Soldermask Bottom")
		(17 "Dwgs.User" user "User.Drawings")
		(19 "Cmts.User" user "User.Comments")
		(21 "Eco1.User" user "User.Eco1")
		(23 "Eco2.User" user "User.Eco2")
		(25 "Edge.Cuts" user "Board Geometry/Outline")
		(27 "Margin" user)
		(31 "F.CrtYd" user "Package Geometry/Place Bound Top")
		(29 "B.CrtYd" user "Package Geometry/Place Bound Bottom")
		(35 "F.Fab" user "Ref Des/Assembly Top")
		(33 "B.Fab" user "Ref Des/Assembly Bottom")
	)
	(footprint ""
		(layer "F.Cu")
		(at 50.292 -135.763)
		(property "Reference" "TP162"
			(at 0 0 0)
			(layer "F.SilkS")
			(hide yes)
			(effects
				(font
					(size 1.27 1.27)
				)
			)
		)
		(property "Value" "TPAD28-2-GP"
			(at -0.0127 -1.6637 0)
			(unlocked yes)
			(layer "F.Fab")
			(hide yes)
			(effects
				(font
					(size 1.016 1.016)
					(thickness 0.1524)
				)
			)
		)
		(property "Device Type" "TPAD28"
			(at -0.0127 -3.1877 0)
			(unlocked yes)
			(layer "F.Fab")
			(hide yes)
			(effects
				(font
					(size 1.016 1.016)
					(thickness 0.1524)
				)
			)
		)
		(duplicate_pad_numbers_are_jumpers no)
		(fp_poly
			(pts
				(arc
					(start 0.3556 0)
					(mid -0.3556 0)
					(end 0.3556 0)
				)
			)
			(stroke
				(width 0)
				(type default)
			)
			(fill no)
			(layer "F.CrtYd")
		)
		(fp_poly
			(pts
				(arc
					(start 0.6096 0)
					(mid -0.6096 0)
					(end 0.6096 0)
				)
			)
			(stroke
				(width 0)
				(type default)
			)
			(fill no)
			(layer "F.Fab")
		)
		(pad "1" smd circle
			(at 0 0)
			(size 0.7112 0.7112)
			(layers "F.Cu" "F.Mask" "F.Paste")
			(net "TP_BMC_GPIOJ7")
		)
	)
	(footprint ""
		(layer "F.Cu")
		(at 162.687 -95.9104 180)
		(property "Reference" "R3108"
			(at 0 0 180)
			(layer "F.SilkS")
			(hide yes)
			(effects
				(font
					(size 1.27 1.27)
				)
			)
		)
		(property "Value" "27R2F-GP"
			(at 0.064008 -3.993896 180)
			(unlocked yes)
			(layer "F.Fab")
			(hide yes)
			(effects
				(font
					(size 1.016 1.016)
					(thickness 0.1524)
				)
			)
		)
		(property "Device Type" "R402H16"
			(at 0.064008 -5.517896 180)
			(unlocked yes)
			(layer "F.Fab")
			(hide yes)
			(effects
				(font
					(size 1.016 1.016)
					(thickness 0.1524)
				)
			)
		)
		(duplicate_pad_numbers_are_jumpers no)
		(fp_line
			(start 0.508 -0.9398)
			(end -0.508 -0.9398)
			(stroke
				(width 0.1524)
				(type default)
			)
			(layer "F.SilkS")
		)
		(fp_line
			(start -0.508 -0.9398)
			(end -0.508 0.9398)
			(stroke
				(width 0.1524)
				(type default)
			)
			(layer "F.SilkS")
		)
		(fp_rect
			(start -0.508 0.9398)
			(end 0.508 -0.9398)
			(stroke
				(width 0)
				(type default)
			)
			(fill no)
			(layer "F.CrtYd")
		)
		(fp_rect
			(start -0.508 0.9398)
			(end 0.508 -0.9398)
			(stroke
				(width 0)
				(type default)
			)
			(fill no)
			(layer "F.Fab")
		)
		(pad "1" smd custom
			(at 0 -0.4445 180)
			(size 0.1397 0.1397)
			(layers "F.Cu" "F.Mask" "F.Paste")
			(net "CLKGEN_P3_R")
			(options
				(clearance outline)
				(anchor circle)
			)
			(primitives
				(gr_poly
					(pts
						(arc
							(start -0.1778 -0.2794)
							(mid -0.249642 -0.249642)
							(end -0.2794 -0.1778)
						)
						(arc
							(start -0.2794 0.1778)
							(mid -0.249642 0.249642)
							(end -0.1778 0.2794)
						)
						(arc
							(start 0.1778 0.2794)
							(mid 0.249642 0.249642)
							(end 0.2794 0.1778)
						)
						(arc
							(start 0.2794 -0.1778)
							(mid 0.249642 -0.249642)
							(end 0.1778 -0.2794)
						)
					)
					(width 0)
					(fill yes)
				)
			)
		)
		(pad "2" smd custom
			(at 0 0.4445 180)
			(size 0.1397 0.1397)
			(layers "F.Cu" "F.Mask" "F.Paste")
			(net "CLKGEN_P3")
			(options
				(clearance outline)
				(anchor circle)
			)
			(primitives
				(gr_poly
					(pts
						(arc
							(start -0.1778 -0.2794)
							(mid -0.249642 -0.249642)
							(end -0.2794 -0.1778)
						)
						(arc
							(start -0.2794 0.1778)
							(mid -0.249642 0.249642)
							(end -0.1778 0.2794)
						)
						(arc
							(start 0.1778 0.2794)
							(mid 0.249642 0.249642)
							(end 0.2794 0.1778)
						)
						(arc
							(start 0.2794 -0.1778)
							(mid 0.249642 -0.249642)
							(end 0.1778 -0.2794)
						)
					)
					(width 0)
					(fill yes)
				)
			)
		)
	)
	(footprint ""
		(layer "F.Cu")
		(at 50.423572 -57.303924 180)
		(property "Reference" "U44"
			(at 0 0 180)
			(layer "F.SilkS")
			(hide yes)
			(effects
				(font
					(size 1.27 1.27)
				)
			)
		)
		(property "Value" "W25Q80DVSSIG-1-GP"
			(at 0 -13.1572 180)
			(unlocked yes)
			(layer "F.Fab")
			(hide yes)
			(effects
				(font
					(size 1.016 1.016)
					(thickness 0.1524)
				)
			)
		)
		(property "Device Type" "SOIC8-1H86"
			(at 0 -14.6812 180)
			(unlocked yes)
			(layer "F.Fab")
			(hide yes)
			(effects
				(font
					(size 1.016 1.016)
					(thickness 0.1524)
				)
			)
		)
		(duplicate_pad_numbers_are_jumpers no)
		(fp_line
			(start 2.1336 2.3876)
			(end -3.048 2.3876)
			(stroke
				(width 0.1524)
				(type default)
			)
			(layer "F.SilkS")
		)
		(fp_line
			(start 2.1336 -2.3876)
			(end 2.1336 2.3876)
			(stroke
				(width 0.1524)
				(type default)
			)
			(layer "F.SilkS")
		)
		(fp_line
			(start 2.1336 -2.3876)
			(end -3.2258 -2.3876)
			(stroke
				(width 0.1524)
				(type default)
			)
			(layer "F.SilkS")
		)
		(fp_line
			(start -2.3114 0)
			(end -3.2258 0.9144)
			(stroke
				(width 0.1524)
				(type default)
			)
			(layer "F.SilkS")
		)
		(fp_line
			(start -2.3114 0)
			(end -3.2258 -0.9144)
			(stroke
				(width 0.1524)
				(type default)
			)
			(layer "F.SilkS")
		)
		(fp_line
			(start -3.048 4.572)
			(end -3.048 2.3876)
			(stroke
				(width 0.508)
				(type default)
			)
			(layer "F.SilkS")
		)
		(fp_line
			(start -3.2258 -2.3876)
			(end -3.2258 4.572)
			(stroke
				(width 0.1524)
				(type default)
			)
			(layer "F.SilkS")
		)
		(fp_poly
			(pts
				(xy -2.2352 2.3876) (xy 2.1336 2.3876) (xy 2.1336 -2.3876) (xy -2.2352 -2.3876)
			)
			(stroke
				(width 0)
				(type default)
			)
			(fill yes)
			(layer "F.SilkS")
		)
		(fp_poly
			(pts
				(xy -3.302 4.826) (xy 3.302 4.826) (xy 3.302 -4.826) (xy -3.302 -4.826)
			)
			(stroke
				(width 0)
				(type default)
			)
			(fill no)
			(layer "F.CrtYd")
		)
		(fp_poly
			(pts
				(xy -3.302 -4.826) (xy 3.302 -4.826) (xy 3.302 4.826) (xy -3.302 4.826)
			)
			(stroke
				(width 0)
				(type default)
			)
			(fill no)
			(layer "F.Fab")
		)
		(pad "1" smd rect
			(at -1.905 3.4925 180)
			(size 0.635 1.651)
			(layers "F.Cu" "F.Mask" "F.Paste")
			(net "NVM_CS_N_R")
		)
		(pad "2" smd rect
			(at -0.635 3.4925 180)
			(size 0.635 1.651)
			(layers "F.Cu" "F.Mask" "F.Paste")
			(net "NVM_SO_R")
		)
		(pad "3" smd rect
			(at 0.635 3.4925 180)
			(size 0.635 1.651)
			(layers "F.Cu" "F.Mask" "F.Paste")
			(net "U44_WP_N")
		)
		(pad "4" smd rect
			(at 1.905 3.4925 180)
			(size 0.635 1.651)
			(layers "F.Cu" "F.Mask" "F.Paste")
			(net "GND")
		)
		(pad "5" smd rect
			(at 1.905 -3.4925 180)
			(size 0.635 1.651)
			(layers "F.Cu" "F.Mask" "F.Paste")
			(net "NVM_SI_R")
		)
		(pad "6" smd rect
			(at 0.635 -3.4925 180)
			(size 0.635 1.651)
			(layers "F.Cu" "F.Mask" "F.Paste")
			(net "NVM_SK_R")
		)
		(pad "7" smd rect
			(at -0.635 -3.4925 180)
			(size 0.635 1.651)
			(layers "F.Cu" "F.Mask" "F.Paste")
			(net "U44_HOLD_N")
		)
		(pad "8" smd rect
			(at -1.905 -3.4925 180)
			(size 0.635 1.651)
			(layers "F.Cu" "F.Mask" "F.Paste")
			(net "P3V3_STBY")
		)
	)
	(footprint ""
		(layer "F.Cu")
		(at 333.40802 -212.420454 180)
		(property "Reference" "C61"
			(at 0 0 180)
			(layer "F.SilkS")
			(hide yes)
			(effects
				(font
					(size 1.27 1.27)
				)
			)
		)
		(property "Value" "SCD22U10V2KX-1GP"
			(at 1.1811 -2.7051 180)
			(unlocked yes)
			(layer "F.Fab")
			(hide yes)
			(effects
				(font
					(size 1.016 1.016)
					(thickness 0.1524)
				)
			)
		)
		(property "Device Type" "C402H22"
			(at 1.1811 -4.2291 180)
			(unlocked yes)
			(layer "F.Fab")
			(hide yes)
			(effects
				(font
					(size 1.016 1.016)
					(thickness 0.1524)
				)
			)
		)
		(duplicate_pad_numbers_are_jumpers no)
		(fp_rect
			(start -0.4318 0.9525)
			(end 0.4318 -0.9525)
			(stroke
				(width 0)
				(type default)
			)
			(fill no)
			(layer "F.CrtYd")
		)
		(fp_rect
			(start -0.4318 0.9525)
			(end 0.4318 -0.9525)
			(stroke
				(width 0)
				(type default)
			)
			(fill no)
			(layer "F.Fab")
		)
		(pad "1" smd custom
			(at 0 -0.4445 180)
			(size 0.1524 0.1524)
			(layers "F.Cu" "F.Mask" "F.Paste")
			(net "PCIE_TX_CAP_N19")
			(options
				(clearance outline)
				(anchor circle)
			)
			(primitives
				(gr_poly
					(pts
						(arc
							(start 0.3048 -0.2032)
							(mid 0.275042 -0.275042)
							(end 0.2032 -0.3048)
						)
						(arc
							(start -0.2032 -0.3048)
							(mid -0.275042 -0.275042)
							(end -0.3048 -0.2032)
						)
						(arc
							(start -0.3048 0.2032)
							(mid -0.275042 0.275042)
							(end -0.2032 0.3048)
						)
						(arc
							(start 0.2032 0.3048)
							(mid 0.275042 0.275042)
							(end 0.3048 0.2032)
						)
					)
					(width 0)
					(fill yes)
				)
			)
		)
		(pad "2" smd custom
			(at 0 0.4445 180)
			(size 0.1524 0.1524)
			(layers "F.Cu" "F.Mask" "F.Paste")
			(net "PCIE_TX_N19")
			(options
				(clearance outline)
				(anchor circle)
			)
			(primitives
				(gr_poly
					(pts
						(arc
							(start 0.3048 -0.2032)
							(mid 0.275042 -0.275042)
							(end 0.2032 -0.3048)
						)
						(arc
							(start -0.2032 -0.3048)
							(mid -0.275042 -0.275042)
							(end -0.3048 -0.2032)
						)
						(arc
							(start -0.3048 0.2032)
							(mid -0.275042 0.275042)
							(end -0.2032 0.3048)
						)
						(arc
							(start 0.2032 0.3048)
							(mid 0.275042 0.275042)
							(end 0.3048 0.2032)
						)
					)
					(width 0)
					(fill yes)
				)
			)
		)
	)
	(footprint ""
		(layer "F.Cu")
		(at 241.681 -23.241 180)
		(property "Reference" "R785"
			(at 0 0 180)
			(layer "F.SilkS")
			(hide yes)
			(effects
				(font
					(size 1.27 1.27)
				)
			)
		)
		(property "Value" "4K7R2F-GP"
			(at 0.064008 -3.993896 180)
			(unlocked yes)
			(layer "F.Fab")
			(hide yes)
			(effects
				(font
					(size 1.016 1.016)
					(thickness 0.1524)
				)
			)
		)
		(property "Device Type" "R402H16"
			(at 0.064008 -5.517896 180)
			(unlocked yes)
			(layer "F.Fab")
			(hide yes)
			(effects
				(font
					(size 1.016 1.016)
					(thickness 0.1524)
				)
			)
		)
		(duplicate_pad_numbers_are_jumpers no)
		(fp_line
			(start 0.508 -0.9398)
			(end -0.508 -0.9398)
			(stroke
				(width 0.1524)
				(type default)
			)
			(layer "F.SilkS")
		)
		(fp_line
			(start -0.508 -0.9398)
			(end -0.508 0.9398)
			(stroke
				(width 0.1524)
				(type default)
			)
			(layer "F.SilkS")
		)
		(fp_rect
			(start -0.508 0.9398)
			(end 0.508 -0.9398)
			(stroke
				(width 0)
				(type default)
			)
			(fill no)
			(layer "F.CrtYd")
		)
		(fp_rect
			(start -0.508 0.9398)
			(end 0.508 -0.9398)
			(stroke
				(width 0)
				(type default)
			)
			(fill no)
			(layer "F.Fab")
		)
		(pad "1" smd custom
			(at 0 -0.4445 180)
			(size 0.1397 0.1397)
			(layers "F.Cu" "F.Mask" "F.Paste")
			(net "BOOTSTRAP5")
			(options
				(clearance outline)
				(anchor circle)
			)
			(primitives
				(gr_poly
					(pts
						(arc
							(start -0.1778 -0.2794)
							(mid -0.249642 -0.249642)
							(end -0.2794 -0.1778)
						)
						(arc
							(start -0.2794 0.1778)
							(mid -0.249642 0.249642)
							(end -0.1778 0.2794)
						)
						(arc
							(start 0.1778 0.2794)
							(mid 0.249642 0.249642)
							(end 0.2794 0.1778)
						)
						(arc
							(start 0.2794 -0.1778)
							(mid 0.249642 -0.249642)
							(end 0.1778 -0.2794)
						)
					)
					(width 0)
					(fill yes)
				)
			)
		)
		(pad "2" smd custom
			(at 0 0.4445 180)
			(size 0.1397 0.1397)
			(layers "F.Cu" "F.Mask" "F.Paste")
			(net "BOOTSTRAP_R_5")
			(options
				(clearance outline)
				(anchor circle)
			)
			(primitives
				(gr_poly
					(pts
						(arc
							(start -0.1778 -0.2794)
							(mid -0.249642 -0.249642)
							(end -0.2794 -0.1778)
						)
						(arc
							(start -0.2794 0.1778)
							(mid -0.249642 0.249642)
							(end -0.1778 0.2794)
						)
						(arc
							(start 0.1778 0.2794)
							(mid 0.249642 0.249642)
							(end 0.2794 0.1778)
						)
						(arc
							(start 0.2794 -0.1778)
							(mid 0.249642 -0.249642)
							(end 0.1778 -0.2794)
						)
					)
					(width 0)
					(fill yes)
				)
			)
		)
	)
	(footprint ""
		(layer "F.Cu")
		(at 335.153 -187.198)
		(property "Reference" "TP169"
			(at 0 0 0)
			(layer "F.SilkS")
			(hide yes)
			(effects
				(font
					(size 1.27 1.27)
				)
			)
		)
		(property "Value" "TPAD28-2-GP"
			(at -0.0127 -1.6637 0)
			(unlocked yes)
			(layer "F.Fab")
			(hide yes)
			(effects
				(font
					(size 1.016 1.016)
					(thickness 0.1524)
				)
			)
		)
		(property "Device Type" "TPAD28"
			(at -0.0127 -3.1877 0)
			(unlocked yes)
			(layer "F.Fab")
			(hide yes)
			(effects
				(font
					(size 1.016 1.016)
					(thickness 0.1524)
				)
			)
		)
		(duplicate_pad_numbers_are_jumpers no)
		(fp_poly
			(pts
				(arc
					(start 0.3556 0)
					(mid -0.3556 0)
					(end 0.3556 0)
				)
			)
			(stroke
				(width 0)
				(type default)
			)
			(fill no)
			(layer "F.CrtYd")
		)
		(fp_poly
			(pts
				(arc
					(start 0.6096 0)
					(mid -0.6096 0)
					(end 0.6096 0)
				)
			)
			(stroke
				(width 0)
				(type default)
			)
			(fill no)
			(layer "F.Fab")
		)
		(pad "1" smd circle
			(at 0 0)
			(size 0.7112 0.7112)
			(layers "F.Cu" "F.Mask" "F.Paste")
			(net "IOEXP4_GPIO12")
		)
	)
	(footprint ""
		(layer "F.Cu")
		(at 29.591 -192.024 90)
		(property "Reference" "R2114"
			(at 0 0 90)
			(layer "F.SilkS")
			(hide yes)
			(effects
				(font
					(size 1.27 1.27)
				)
			)
		)
		(property "Value" "0R2J-2-GP"
			(at 0.064008 -3.993896 90)
			(unlocked yes)
			(layer "F.Fab")
			(hide yes)
			(effects
				(font
					(size 1.016 1.016)
					(thickness 0.1524)
				)
			)
		)
		(property "Device Type" "R402H16"
			(at 0.064008 -5.517896 90)
			(unlocked yes)
			(layer "F.Fab")
			(hide yes)
			(effects
				(font
					(size 1.016 1.016)
					(thickness 0.1524)
				)
			)
		)
		(duplicate_pad_numbers_are_jumpers no)
		(fp_line
			(start 0.508 -0.9398)
			(end -0.508 -0.9398)
			(stroke
				(width 0.1524)
				(type default)
			)
			(layer "F.SilkS")
		)
		(fp_line
			(start -0.508 -0.9398)
			(end -0.508 0.9398)
			(stroke
				(width 0.1524)
				(type default)
			)
			(layer "F.SilkS")
		)
		(fp_rect
			(start -0.508 0.9398)
			(end 0.508 -0.9398)
			(stroke
				(width 0)
				(type default)
			)
			(fill no)
			(layer "F.CrtYd")
		)
		(fp_rect
			(start -0.508 0.9398)
			(end 0.508 -0.9398)
			(stroke
				(width 0)
				(type default)
			)
			(fill no)
			(layer "F.Fab")
		)
		(pad "1" smd custom
			(at 0 -0.4445 90)
			(size 0.1397 0.1397)
			(layers "F.Cu" "F.Mask" "F.Paste")
			(net "MB0_CM_GATE")
			(options
				(clearance outline)
				(anchor circle)
			)
			(primitives
				(gr_poly
					(pts
						(arc
							(start -0.1778 -0.2794)
							(mid -0.249642 -0.249642)
							(end -0.2794 -0.1778)
						)
						(arc
							(start -0.2794 0.1778)
							(mid -0.249642 0.249642)
							(end -0.1778 0.2794)
						)
						(arc
							(start 0.1778 0.2794)
							(mid 0.249642 0.249642)
							(end 0.2794 0.1778)
						)
						(arc
							(start 0.2794 -0.1778)
							(mid 0.249642 -0.249642)
							(end 0.1778 -0.2794)
						)
					)
					(width 0)
					(fill yes)
				)
			)
		)
		(pad "2" smd custom
			(at 0 0.4445 90)
			(size 0.1397 0.1397)
			(layers "F.Cu" "F.Mask" "F.Paste")
			(net "MB0_CM_GATE_R")
			(options
				(clearance outline)
				(anchor circle)
			)
			(primitives
				(gr_poly
					(pts
						(arc
							(start -0.1778 -0.2794)
							(mid -0.249642 -0.249642)
							(end -0.2794 -0.1778)
						)
						(arc
							(start -0.2794 0.1778)
							(mid -0.249642 0.249642)
							(end -0.1778 0.2794)
						)
						(arc
							(start 0.1778 0.2794)
							(mid 0.249642 0.249642)
							(end 0.2794 0.1778)
						)
						(arc
							(start 0.2794 -0.1778)
							(mid 0.249642 -0.249642)
							(end 0.1778 -0.2794)
						)
					)
					(width 0)
					(fill yes)
				)
			)
		)
	)
	(footprint ""
		(layer "F.Cu")
		(at 36.195254 -104.427274 90)
		(property "Reference" "R33"
			(at 0 0 90)
			(layer "F.SilkS")
			(hide yes)
			(effects
				(font
					(size 1.27 1.27)
				)
			)
		)
		(property "Value" "0R3J-0-U-GP"
			(at -0.0254 -2.5146 90)
			(unlocked yes)
			(layer "F.Fab")
			(hide yes)
			(effects
				(font
					(size 1.016 1.016)
					(thickness 0.1524)
				)
			)
		)
		(property "Device Type" "R603H22"
			(at -0.0254 -4.0386 90)
			(unlocked yes)
			(layer "F.Fab")
			(hide yes)
			(effects
				(font
					(size 1.016 1.016)
					(thickness 0.1524)
				)
			)
		)
		(duplicate_pad_numbers_are_jumpers no)
		(fp_line
			(start 0.2032 0)
			(end 0.4826 0)
			(stroke
				(width 0.2032)
				(type default)
			)
			(layer "F.SilkS")
		)
		(fp_line
			(start -0.4826 0)
			(end -0.2032 0)
			(stroke
				(width 0.2032)
				(type default)
			)
			(layer "F.SilkS")
		)
		(fp_rect
			(start -0.5842 1.3335)
			(end 0.5842 -1.3335)
			(stroke
				(width 0)
				(type default)
			)
			(fill no)
			(layer "F.CrtYd")
		)
		(fp_rect
			(start -0.5842 1.3335)
			(end 0.5842 -1.3335)
			(stroke
				(width 0)
				(type default)
			)
			(fill no)
			(layer "F.Fab")
		)
		(pad "1" smd custom
			(at 0 -0.762 90)
			(size 0.2159 0.2159)
			(layers "F.Cu" "F.Mask" "F.Paste")
			(net "P3V3_I2C_MUX")
			(options
				(clearance outline)
				(anchor circle)
			)
			(primitives
				(gr_poly
					(pts
						(arc
							(start -0.3302 -0.4318)
							(mid -0.402042 -0.402042)
							(end -0.4318 -0.3302)
						)
						(arc
							(start -0.4318 0.3302)
							(mid -0.402042 0.402042)
							(end -0.3302 0.4318)
						)
						(arc
							(start 0.3302 0.4318)
							(mid 0.402042 0.402042)
							(end 0.4318 0.3302)
						)
						(arc
							(start 0.4318 -0.3302)
							(mid 0.402042 -0.402042)
							(end 0.3302 -0.4318)
						)
					)
					(width 0)
					(fill yes)
				)
			)
		)
		(pad "2" smd custom
			(at 0 0.762 90)
			(size 0.2159 0.2159)
			(layers "F.Cu" "F.Mask" "F.Paste")
			(net "P3V3_STBY")
			(options
				(clearance outline)
				(anchor circle)
			)
			(primitives
				(gr_poly
					(pts
						(arc
							(start -0.3302 -0.4318)
							(mid -0.402042 -0.402042)
							(end -0.4318 -0.3302)
						)
						(arc
							(start -0.4318 0.3302)
							(mid -0.402042 0.402042)
							(end -0.3302 0.4318)
						)
						(arc
							(start 0.3302 0.4318)
							(mid 0.402042 0.402042)
							(end 0.4318 0.3302)
						)
						(arc
							(start 0.4318 -0.3302)
							(mid 0.402042 -0.402042)
							(end 0.3302 -0.4318)
						)
					)
					(width 0)
					(fill yes)
				)
			)
		)
	)
)
